# SCM (Grand Teton) — schematic netlist excerpt (pin names and nets, part order shuffled) for the footprints in the layout excerpt that follows; sources: Cadence DE-HDL packaged netlist, KiCad conversion of 12092022_DA0F0TMDCD0_F0T_Management_Board_D_brd_V3_OCP.brd

R419  Q_RES  1K 1% CHIP  pkg 0402LF  page 26 : A = TMC75_A2 ; B = GND
R719  Q_RES  0 5% EMPTY  pkg 0402LF  page 28 : A = PWRGD_PSU_AC_PWROK ; B = PWRGD_DSW_PWROK_R3

(kicad_pcb
	(version 20260206)
	(generator "pcbnew")
	(generator_version "10.0")
	(general
		(thickness 1.6)
		(legacy_teardrops no)
	)
	(paper "A4")
	(title_block
		(title "12092022_DA0F0TMDCD0_F0T_Management_Board_D_brd_V3_OCP.brd")
		(comment 1 "Grand Teton / footprints 1113-1114 of 1440")
	)
	(layers
		(0 "F.Cu" signal "TOP")
		(4 "In1.Cu" signal "GND")
		(6 "In2.Cu" signal "IN1")
		(8 "In3.Cu" signal "GND1")
		(10 "In4.Cu" signal "IN2")
		(12 "In5.Cu" signal "VCC")
		(14 "In6.Cu" signal "VCC1")
		(16 "In7.Cu" signal "IN3")
		(18 "In8.Cu" signal "GND2")
		(20 "In9.Cu" signal "IN4")
		(22 "In10.Cu" signal "GND3")
		(2 "B.Cu" signal "BOTTOM")
		(9 "F.Adhes" user "F.Adhesive")
		(11 "B.Adhes" user "B.Adhesive")
		(13 "F.Paste" user "Package Geometry/Pastemask Top")
		(15 "B.Paste" user "Package Geometry/Pastemask Bottom")
		(5 "F.SilkS" user "Ref Des/Silkscreen Top")
		(7 "B.SilkS" user "Ref Des/Silkscreen Bottom")
		(1 "F.Mask" user "Board Geometry/Soldermask Top")
		(3 "B.Mask" user "Board Geometry/Soldermask Bottom")
		(17 "Dwgs.User" user "User.Drawings")
		(19 "Cmts.User" user "User.Comments")
		(21 "Eco1.User" user "User.Eco1")
		(23 "Eco2.User" user "User.Eco2")
		(25 "Edge.Cuts" user "Board Geometry/Outline")
		(27 "Margin" user)
		(31 "F.CrtYd" user "Package Geometry/Place Bound Top")
		(29 "B.CrtYd" user "Package Geometry/Place Bound Bottom")
		(35 "F.Fab" user "Ref Des/Assembly Top")
		(33 "B.Fab" user "Ref Des/Assembly Bottom")
	)
	(footprint ""
		(layer "B.Cu")
		(at 51.2445 -87.8205 180)
		(property "Reference" "R719"
			(at 0 0 0)
			(layer "B.SilkS")
			(hide yes)
			(effects
				(font
					(size 1.27 1.27)
				)
				(justify mirror)
			)
		)
		(property "Value" ""
			(at 0 0 0)
			(layer "B.Fab")
			(effects
				(font
					(size 1.27 1.27)
				)
				(justify mirror)
			)
		)
		(duplicate_pad_numbers_are_jumpers no)
		(fp_line
			(start 0.7874 0.4064)
			(end 0.7874 -0.4064)
			(stroke
				(width 0.1524)
				(type default)
			)
			(layer "B.SilkS")
		)
		(fp_line
			(start 0.7874 -0.4064)
			(end -0.7874 -0.4064)
			(stroke
				(width 0.1524)
				(type default)
			)
			(layer "B.SilkS")
		)
		(fp_line
			(start -0.7874 0.4064)
			(end 0.7874 0.4064)
			(stroke
				(width 0.1524)
				(type default)
			)
			(layer "B.SilkS")
		)
		(fp_line
			(start -0.7874 -0.4064)
			(end -0.7874 0.4064)
			(stroke
				(width 0.1524)
				(type default)
			)
			(layer "B.SilkS")
		)
		(fp_line
			(start 0.67945 0.3048)
			(end 0.67945 -0.305054)
			(stroke
				(width 0.1)
				(type default)
			)
			(layer "B.Fab")
		)
		(fp_line
			(start 0.67945 -0.305054)
			(end 0.12065 -0.305054)
			(stroke
				(width 0.1)
				(type default)
			)
			(layer "B.Fab")
		)
		(fp_line
			(start 0.12065 0.3048)
			(end 0.67945 0.3048)
			(stroke
				(width 0.1)
				(type default)
			)
			(layer "B.Fab")
		)
		(fp_line
			(start 0.12065 0.2794)
			(end 0.12065 0.3048)
			(stroke
				(width 0.1)
				(type default)
			)
			(layer "B.Fab")
		)
		(fp_line
			(start 0.12065 -0.2794)
			(end -0.12065 -0.2794)
			(stroke
				(width 0.1)
				(type default)
			)
			(layer "B.Fab")
		)
		(fp_line
			(start 0.12065 -0.305054)
			(end 0.12065 -0.2794)
			(stroke
				(width 0.1)
				(type default)
			)
			(layer "B.Fab")
		)
		(fp_line
			(start -0.120396 0.3048)
			(end -0.120396 0.2794)
			(stroke
				(width 0.1)
				(type default)
			)
			(layer "B.Fab")
		)
		(fp_line
			(start -0.120396 0.2794)
			(end 0.12065 0.2794)
			(stroke
				(width 0.1)
				(type default)
			)
			(layer "B.Fab")
		)
		(fp_line
			(start -0.12065 -0.2794)
			(end -0.12065 -0.3048)
			(stroke
				(width 0.1)
				(type default)
			)
			(layer "B.Fab")
		)
		(fp_line
			(start -0.12065 -0.3048)
			(end -0.67945 -0.3048)
			(stroke
				(width 0.1)
				(type default)
			)
			(layer "B.Fab")
		)
		(fp_line
			(start -0.67945 0.3048)
			(end -0.120396 0.3048)
			(stroke
				(width 0.1)
				(type default)
			)
			(layer "B.Fab")
		)
		(fp_line
			(start -0.67945 -0.3048)
			(end -0.67945 0.3048)
			(stroke
				(width 0.1)
				(type default)
			)
			(layer "B.Fab")
		)
		(pad "1" smd circle
			(at 0.40005 0)
			(size 0 0)
			(layers "B.Cu" "B.Mask" "B.Paste")
			(net "PWRGD_PSU_AC_PWROK")
		)
		(pad "2" smd circle
			(at -0.40005 0)
			(size 0 0)
			(layers "B.Cu" "B.Mask" "B.Paste")
			(net "PWRGD_DSW_PWROK_R3")
		)
	)
	(footprint ""
		(layer "B.Cu")
		(at 24.003 -18.034 90)
		(property "Reference" "R419"
			(at 0 0 90)
			(layer "B.SilkS")
			(hide yes)
			(effects
				(font
					(size 1.27 1.27)
				)
				(justify mirror)
			)
		)
		(property "Value" ""
			(at 0 0 90)
			(layer "B.Fab")
			(effects
				(font
					(size 1.27 1.27)
				)
				(justify mirror)
			)
		)
		(duplicate_pad_numbers_are_jumpers no)
		(fp_line
			(start 0.7874 -0.4064)
			(end -0.7874 -0.4064)
			(stroke
				(width 0.1524)
				(type default)
			)
			(layer "B.SilkS")
		)
		(fp_line
			(start -0.7874 -0.4064)
			(end -0.7874 0.4064)
			(stroke
				(width 0.1524)
				(type default)
			)
			(layer "B.SilkS")
		)
		(fp_line
			(start 0.7874 0.4064)
			(end 0.7874 -0.4064)
			(stroke
				(width 0.1524)
				(type default)
			)
			(layer "B.SilkS")
		)
		(fp_line
			(start -0.7874 0.4064)
			(end 0.7874 0.4064)
			(stroke
				(width 0.1524)
				(type default)
			)
			(layer "B.SilkS")
		)
		(fp_line
			(start 0.67945 -0.305054)
			(end 0.12065 -0.305054)
			(stroke
				(width 0.1)
				(type default)
			)
			(layer "B.Fab")
		)
		(fp_line
			(start 0.12065 -0.305054)
			(end 0.12065 -0.2794)
			(stroke
				(width 0.1)
				(type default)
			)
			(layer "B.Fab")
		)
		(fp_line
			(start -0.12065 -0.3048)
			(end -0.67945 -0.3048)
			(stroke
				(width 0.1)
				(type default)
			)
			(layer "B.Fab")
		)
		(fp_line
			(start -0.67945 -0.3048)
			(end -0.67945 0.3048)
			(stroke
				(width 0.1)
				(type default)
			)
			(layer "B.Fab")
		)
		(fp_line
			(start 0.12065 -0.2794)
			(end -0.12065 -0.2794)
			(stroke
				(width 0.1)
				(type default)
			)
			(layer "B.Fab")
		)
		(fp_line
			(start -0.12065 -0.2794)
			(end -0.12065 -0.3048)
			(stroke
				(width 0.1)
				(type default)
			)
			(layer "B.Fab")
		)
		(fp_line
			(start 0.12065 0.2794)
			(end 0.12065 0.3048)
			(stroke
				(width 0.1)
				(type default)
			)
			(layer "B.Fab")
		)
		(fp_line
			(start -0.120396 0.2794)
			(end 0.12065 0.2794)
			(stroke
				(width 0.1)
				(type default)
			)
			(layer "B.Fab")
		)
		(fp_line
			(start 0.67945 0.3048)
			(end 0.67945 -0.305054)
			(stroke
				(width 0.1)
				(type default)
			)
			(layer "B.Fab")
		)
		(fp_line
			(start 0.12065 0.3048)
			(end 0.67945 0.3048)
			(stroke
				(width 0.1)
				(type default)
			)
			(layer "B.Fab")
		)
		(fp_line
			(start -0.120396 0.3048)
			(end -0.120396 0.2794)
			(stroke
				(width 0.1)
				(type default)
			)
			(layer "B.Fab")
		)
		(fp_line
			(start -0.67945 0.3048)
			(end -0.120396 0.3048)
			(stroke
				(width 0.1)
				(type default)
			)
			(layer "B.Fab")
		)
		(pad "1" smd circle
			(at 0.40005 0 270)
			(size 0 0)
			(layers "B.Cu" "B.Mask" "B.Paste")
			(net "TMC75_A2")
		)
		(pad "2" smd circle
			(at -0.40005 0 270)
			(size 0 0)
			(layers "B.Cu" "B.Mask" "B.Paste")
			(net "GND")
		)
	)
)
